(kicad_pcb
	(version 20260206)
	(generator "pcbnew")
	(generator_version "10.0")
	(general
		(thickness 1.6)
		(legacy_teardrops no)
	)
	(paper "A4")
	(title_block
		(title "panther-plus-userver — 13130-1b_20150205.brd")
		(comment 1 "Honey Badger (Wiwynn) / footprint 406 of 1509 (DIMM2), pads 100-106 of 210")
	)
	(layers
		(0 "F.Cu" signal "TOP")
		(4 "In1.Cu" signal "L2")
		(6 "In2.Cu" signal "L3")
		(8 "In3.Cu" signal "L4")
		(10 "In4.Cu" signal "L5")
		(12 "In5.Cu" signal "L6")
		(14 "In6.Cu" signal "L7")
		(16 "In7.Cu" signal "L8")
		(18 "In8.Cu" signal "L9")
		(20 "In9.Cu" signal "L10")
		(22 "In10.Cu" signal "L11")
		(2 "B.Cu" signal "BOTTOM")
		(9 "F.Adhes" user "F.Adhesive")
		(11 "B.Adhes" user "B.Adhesive")
		(13 "F.Paste" user "Package Geometry/Pastemask Top")
		(15 "B.Paste" user "Package Geometry/Pastemask Bottom")
		(5 "F.SilkS" user "Ref Des/Silkscreen Top")
		(7 "B.SilkS" user "Ref Des/Silkscreen Bottom")
		(1 "F.Mask" user "Board Geometry/Soldermask Top")
		(3 "B.Mask" user "Board Geometry/Soldermask Bottom")
		(17 "Dwgs.User" user "User.Drawings")
		(19 "Cmts.User" user "User.Comments")
		(21 "Eco1.User" user "User.Eco1")
		(23 "Eco2.User" user "User.Eco2")
		(25 "Edge.Cuts" user "Board Geometry/Outline")
		(27 "Margin" user)
		(31 "F.CrtYd" user "Package Geometry/Place Bound Top")
		(29 "B.CrtYd" user "Package Geometry/Place Bound Bottom")
		(35 "F.Fab" user "Ref Des/Assembly Top")
		(33 "B.Fab" user "Ref Des/Assembly Bottom")
	)
	(footprint ""
		(layer "F.Cu")
		(at 158.500064 -66.699892 180)
		(property "Reference" "DIMM2"
			(at 0 0 180)
			(layer "F.SilkS")
			(hide yes)
			(effects
				(font
					(size 1.27 1.27)
				)
			)
		)
		(property "Value" "DDR3-204P-174-COLAY-1-GP"
			(at -40.682164 -17.468088 180)
			(unlocked yes)
			(layer "F.Fab")
			(hide yes)
			(effects
				(font
					(size 1.016 1.016)
					(thickness 0.1524)
				)
			)
		)
		(property "Device Type" "AS0A626-H8SN-7H-COLAY-1"
			(at -40.682164 -18.992088 180)
			(unlocked yes)
			(layer "F.Fab")
			(hide yes)
			(effects
				(font
					(size 1.016 1.016)
					(thickness 0.1524)
				)
			)
		)
		(duplicate_pad_numbers_are_jumpers no)
		(pad "98" smd custom
			(at -0.150114 -4.106672 180)
			(size 0.1143 0.1143)
			(layers "F.Cu" "F.Mask" "F.Paste")
			(net "M_A_MA7")
			(options
				(clearance outline)
				(anchor circle)
			)
			(primitives
				(gr_poly
					(pts
						(xy 0 0.9017) (xy -0.03175 0.89916) (xy -0.0635 0.889) (xy -0.09144 0.87376) (xy -0.11684 0.85344)
						(xy -0.13716 0.82804) (xy -0.1524 0.8001) (xy -0.16256 0.76835) (xy -0.1651 0.7366) (xy -0.1651 0.44958)
						(xy -0.17272 0.44196) (xy -0.19812 0.4064) (xy -0.2032 0.39624) (xy -0.20701 0.38735) (xy -0.21209 0.37719)
						(xy -0.2159 0.36703) (xy -0.21844 0.35687) (xy -0.22225 0.34544) (xy -0.22352 0.33528) (xy -0.22606 0.32512)
						(xy -0.22733 0.31369) (xy -0.22733 0.30353) (xy -0.2286 0.2921) (xy -0.22733 0.28067) (xy -0.22733 0.27051)
						(xy -0.22606 0.25908) (xy -0.22352 0.24892) (xy -0.22225 0.23876) (xy -0.21844 0.22733) (xy -0.2159 0.21717)
						(xy -0.21209 0.20701) (xy -0.20701 0.19685) (xy -0.2032 0.18796) (xy -0.19812 0.1778) (xy -0.17272 0.14224)
						(xy -0.1651 0.13462) (xy -0.1651 -0.7366) (xy -0.16256 -0.76835) (xy -0.1524 -0.8001) (xy -0.13716 -0.82804)
						(xy -0.11684 -0.85344) (xy -0.09144 -0.87376) (xy -0.0635 -0.889) (xy -0.03175 -0.89916) (xy 0 -0.9017)
						(xy 0.03175 -0.89916) (xy 0.0635 -0.889) (xy 0.09144 -0.87376) (xy 0.11684 -0.85344) (xy 0.13716 -0.82804)
						(xy 0.1524 -0.8001) (xy 0.16256 -0.76835) (xy 0.1651 -0.7366) (xy 0.1651 0.13462) (xy 0.17272 0.14224)
						(xy 0.19812 0.1778) (xy 0.2032 0.18796) (xy 0.20701 0.19685) (xy 0.21209 0.20701) (xy 0.2159 0.21717)
						(xy 0.21844 0.22733) (xy 0.22225 0.23876) (xy 0.22352 0.24892) (xy 0.22606 0.25908) (xy 0.22733 0.27051)
						(xy 0.22733 0.28067) (xy 0.2286 0.2921) (xy 0.22733 0.30353) (xy 0.22733 0.31369) (xy 0.22606 0.32512)
						(xy 0.22352 0.33528) (xy 0.22225 0.34544) (xy 0.21844 0.35687) (xy 0.2159 0.36703) (xy 0.21209 0.37719)
						(xy 0.20701 0.38735) (xy 0.2032 0.39624) (xy 0.19812 0.4064) (xy 0.17272 0.44196) (xy 0.1651 0.44958)
						(xy 0.1651 0.7366) (xy 0.16256 0.76835) (xy 0.1524 0.8001) (xy 0.13716 0.82804) (xy 0.11684 0.85344)
						(xy 0.09144 0.87376) (xy 0.0635 0.889) (xy 0.03175 0.89916)
					)
					(width 0)
					(fill yes)
				)
			)
		)
		(pad "99" smd custom
			(at 0.150114 4.106672 180)
			(size 0.1143 0.1143)
			(layers "F.Cu" "F.Mask" "F.Paste")
			(net "M_A_MA5")
			(options
				(clearance outline)
				(anchor circle)
			)
			(primitives
				(gr_poly
					(pts
						(xy 0 0.9017) (xy -0.03175 0.89916) (xy -0.0635 0.889) (xy -0.09144 0.87376) (xy -0.11684 0.85344)
						(xy -0.13716 0.82804) (xy -0.1524 0.8001) (xy -0.16256 0.76835) (xy -0.1651 0.7366) (xy -0.1651 0.11938)
						(xy -0.17272 0.11176) (xy -0.19812 0.0762) (xy -0.2032 0.06604) (xy -0.20701 0.05715) (xy -0.21209 0.04699)
						(xy -0.2159 0.03683) (xy -0.21844 0.02667) (xy -0.22225 0.01524) (xy -0.22352 0.00508) (xy -0.22606 -0.00508)
						(xy -0.22733 -0.01651) (xy -0.22733 -0.02667) (xy -0.2286 -0.0381) (xy -0.22733 -0.04953) (xy -0.22733 -0.05969)
						(xy -0.22606 -0.07112) (xy -0.22352 -0.08128) (xy -0.22225 -0.09144) (xy -0.21844 -0.10287) (xy -0.2159 -0.11303)
						(xy -0.21209 -0.12319) (xy -0.20701 -0.13335) (xy -0.2032 -0.14224) (xy -0.19812 -0.1524) (xy -0.17272 -0.18796)
						(xy -0.1651 -0.19558) (xy -0.1651 -0.7366) (xy -0.16256 -0.76835) (xy -0.1524 -0.8001) (xy -0.13716 -0.82804)
						(xy -0.11684 -0.85344) (xy -0.09144 -0.87376) (xy -0.0635 -0.889) (xy -0.03175 -0.89916) (xy 0 -0.9017)
						(xy 0.03175 -0.89916) (xy 0.0635 -0.889) (xy 0.09144 -0.87376) (xy 0.11684 -0.85344) (xy 0.13716 -0.82804)
						(xy 0.1524 -0.8001) (xy 0.16256 -0.76835) (xy 0.1651 -0.7366) (xy 0.1651 -0.19685) (xy 0.17272 -0.18923)
						(xy 0.17907 -0.18034) (xy 0.18669 -0.17145) (xy 0.19177 -0.16256) (xy 0.19812 -0.15367) (xy 0.20828 -0.13335)
						(xy 0.21971 -0.10287) (xy 0.22225 -0.09271) (xy 0.22479 -0.08128) (xy 0.22606 -0.07112) (xy 0.2286 -0.05969)
						(xy 0.2286 -0.01651) (xy 0.22606 -0.00508) (xy 0.22479 0.00508) (xy 0.22225 0.01651) (xy 0.21971 0.02667)
						(xy 0.20828 0.05715) (xy 0.19812 0.07747) (xy 0.19177 0.08636) (xy 0.18669 0.09525) (xy 0.17907 0.10414)
						(xy 0.17272 0.11303) (xy 0.1651 0.12065) (xy 0.1651 0.7366) (xy 0.16256 0.76835) (xy 0.1524 0.8001)
						(xy 0.13716 0.82804) (xy 0.11684 0.85344) (xy 0.09144 0.87376) (xy 0.0635 0.889) (xy 0.03175 0.89916)
					)
					(width 0)
					(fill yes)
				)
			)
		)
		(pad "100" smd custom
			(at 0.450088 -4.106672 180)
			(size 0.1143 0.1143)
			(layers "F.Cu" "F.Mask" "F.Paste")
			(net "M_A_MA6")
			(options
				(clearance outline)
				(anchor circle)
			)
			(primitives
				(gr_poly
					(pts
						(xy 0 0.9017) (xy -0.03175 0.89916) (xy -0.0635 0.889) (xy -0.09144 0.87376) (xy -0.11684 0.85344)
						(xy -0.13716 0.82804) (xy -0.1524 0.8001) (xy -0.16256 0.76835) (xy -0.1651 0.7366) (xy -0.1651 0.19685)
						(xy -0.17272 0.18923) (xy -0.17907 0.18034) (xy -0.18669 0.17145) (xy -0.19177 0.16256) (xy -0.19812 0.15367)
						(xy -0.20828 0.13335) (xy -0.21971 0.10287) (xy -0.22225 0.09271) (xy -0.22479 0.08128) (xy -0.22606 0.07112)
						(xy -0.2286 0.05969) (xy -0.2286 0.01651) (xy -0.22606 0.00508) (xy -0.22479 -0.00508) (xy -0.22225 -0.01651)
						(xy -0.21971 -0.02667) (xy -0.20828 -0.05715) (xy -0.19812 -0.07747) (xy -0.19177 -0.08636) (xy -0.18669 -0.09525)
						(xy -0.17907 -0.10414) (xy -0.17272 -0.11303) (xy -0.1651 -0.12065) (xy -0.1651 -0.7366) (xy -0.16256 -0.76835)
						(xy -0.1524 -0.8001) (xy -0.13716 -0.82804) (xy -0.11684 -0.85344) (xy -0.09144 -0.87376) (xy -0.0635 -0.889)
						(xy -0.03175 -0.89916) (xy 0 -0.9017) (xy 0.03175 -0.89916) (xy 0.0635 -0.889) (xy 0.09144 -0.87376)
						(xy 0.11684 -0.85344) (xy 0.13716 -0.82804) (xy 0.1524 -0.8001) (xy 0.16256 -0.76835) (xy 0.1651 -0.7366)
						(xy 0.1651 -0.11938) (xy 0.17272 -0.11176) (xy 0.19812 -0.0762) (xy 0.2032 -0.06604) (xy 0.20701 -0.05715)
						(xy 0.21209 -0.04699) (xy 0.2159 -0.03683) (xy 0.21844 -0.02667) (xy 0.22225 -0.01524) (xy 0.22352 -0.00508)
						(xy 0.22606 0.00508) (xy 0.22733 0.01651) (xy 0.22733 0.02667) (xy 0.2286 0.0381) (xy 0.22733 0.04953)
						(xy 0.22733 0.05969) (xy 0.22606 0.07112) (xy 0.22352 0.08128) (xy 0.22225 0.09144) (xy 0.21844 0.10287)
						(xy 0.2159 0.11303) (xy 0.21209 0.12319) (xy 0.20701 0.13335) (xy 0.2032 0.14224) (xy 0.19812 0.1524)
						(xy 0.17272 0.18796) (xy 0.1651 0.19558) (xy 0.1651 0.7366) (xy 0.16256 0.76835) (xy 0.1524 0.8001)
						(xy 0.13716 0.82804) (xy 0.11684 0.85344) (xy 0.09144 0.87376) (xy 0.0635 0.889) (xy 0.03175 0.89916)
					)
					(width 0)
					(fill yes)
				)
			)
		)
		(pad "101" smd custom
			(at 0.750062 4.106672 180)
			(size 0.1143 0.1143)
			(layers "F.Cu" "F.Mask" "F.Paste")
			(net "PV_VDDR")
			(options
				(clearance outline)
				(anchor circle)
			)
			(primitives
				(gr_poly
					(pts
						(xy 0 0.9017) (xy -0.03175 0.89916) (xy -0.0635 0.889) (xy -0.09144 0.87376) (xy -0.11684 0.85344)
						(xy -0.13716 0.82804) (xy -0.1524 0.8001) (xy -0.16256 0.76835) (xy -0.1651 0.7366) (xy -0.1651 -0.13462)
						(xy -0.17272 -0.14224) (xy -0.19812 -0.1778) (xy -0.2032 -0.18796) (xy -0.20701 -0.19685) (xy -0.21209 -0.20701)
						(xy -0.2159 -0.21717) (xy -0.21844 -0.22733) (xy -0.22225 -0.23876) (xy -0.22352 -0.24892) (xy -0.22606 -0.25908)
						(xy -0.22733 -0.27051) (xy -0.22733 -0.28067) (xy -0.2286 -0.2921) (xy -0.22733 -0.30353) (xy -0.22733 -0.31369)
						(xy -0.22606 -0.32512) (xy -0.22352 -0.33528) (xy -0.22225 -0.34544) (xy -0.21844 -0.35687) (xy -0.2159 -0.36703)
						(xy -0.21209 -0.37719) (xy -0.20701 -0.38735) (xy -0.2032 -0.39624) (xy -0.19812 -0.4064) (xy -0.17272 -0.44196)
						(xy -0.1651 -0.44958) (xy -0.1651 -0.7366) (xy -0.16256 -0.76835) (xy -0.1524 -0.8001) (xy -0.13716 -0.82804)
						(xy -0.11684 -0.85344) (xy -0.09144 -0.87376) (xy -0.0635 -0.889) (xy -0.03175 -0.89916) (xy 0 -0.9017)
						(xy 0.03175 -0.89916) (xy 0.0635 -0.889) (xy 0.09144 -0.87376) (xy 0.11684 -0.85344) (xy 0.13716 -0.82804)
						(xy 0.1524 -0.8001) (xy 0.16256 -0.76835) (xy 0.1651 -0.7366) (xy 0.1651 -0.44958) (xy 0.17272 -0.44196)
						(xy 0.19812 -0.4064) (xy 0.2032 -0.39624) (xy 0.20701 -0.38735) (xy 0.21209 -0.37719) (xy 0.2159 -0.36703)
						(xy 0.21844 -0.35687) (xy 0.22225 -0.34544) (xy 0.22352 -0.33528) (xy 0.22606 -0.32512) (xy 0.22733 -0.31369)
						(xy 0.22733 -0.30353) (xy 0.2286 -0.2921) (xy 0.22733 -0.28067) (xy 0.22733 -0.27051) (xy 0.22606 -0.25908)
						(xy 0.22352 -0.24892) (xy 0.22225 -0.23876) (xy 0.21844 -0.22733) (xy 0.2159 -0.21717) (xy 0.21209 -0.20701)
						(xy 0.20701 -0.19685) (xy 0.2032 -0.18796) (xy 0.19812 -0.1778) (xy 0.17272 -0.14224) (xy 0.1651 -0.13462)
						(xy 0.1651 0.7366) (xy 0.16256 0.76835) (xy 0.1524 0.8001) (xy 0.13716 0.82804) (xy 0.11684 0.85344)
						(xy 0.09144 0.87376) (xy 0.0635 0.889) (xy 0.03175 0.89916)
					)
					(width 0)
					(fill yes)
				)
			)
		)
		(pad "102" smd custom
			(at 1.050036 -4.106672 180)
			(size 0.1143 0.1143)
			(layers "F.Cu" "F.Mask" "F.Paste")
			(net "PV_VDDR")
			(options
				(clearance outline)
				(anchor circle)
			)
			(primitives
				(gr_poly
					(pts
						(xy 0 0.9017) (xy -0.03175 0.89916) (xy -0.0635 0.889) (xy -0.09144 0.87376) (xy -0.11684 0.85344)
						(xy -0.13716 0.82804) (xy -0.1524 0.8001) (xy -0.16256 0.76835) (xy -0.1651 0.7366) (xy -0.1651 0.44958)
						(xy -0.17272 0.44196) (xy -0.19812 0.4064) (xy -0.2032 0.39624) (xy -0.20701 0.38735) (xy -0.21209 0.37719)
						(xy -0.2159 0.36703) (xy -0.21844 0.35687) (xy -0.22225 0.34544) (xy -0.22352 0.33528) (xy -0.22606 0.32512)
						(xy -0.22733 0.31369) (xy -0.22733 0.30353) (xy -0.2286 0.2921) (xy -0.22733 0.28067) (xy -0.22733 0.27051)
						(xy -0.22606 0.25908) (xy -0.22352 0.24892) (xy -0.22225 0.23876) (xy -0.21844 0.22733) (xy -0.2159 0.21717)
						(xy -0.21209 0.20701) (xy -0.20701 0.19685) (xy -0.2032 0.18796) (xy -0.19812 0.1778) (xy -0.17272 0.14224)
						(xy -0.1651 0.13462) (xy -0.1651 -0.7366) (xy -0.16256 -0.76835) (xy -0.1524 -0.8001) (xy -0.13716 -0.82804)
						(xy -0.11684 -0.85344) (xy -0.09144 -0.87376) (xy -0.0635 -0.889) (xy -0.03175 -0.89916) (xy 0 -0.9017)
						(xy 0.03175 -0.89916) (xy 0.0635 -0.889) (xy 0.09144 -0.87376) (xy 0.11684 -0.85344) (xy 0.13716 -0.82804)
						(xy 0.1524 -0.8001) (xy 0.16256 -0.76835) (xy 0.1651 -0.7366) (xy 0.1651 0.13462) (xy 0.17272 0.14224)
						(xy 0.19812 0.1778) (xy 0.2032 0.18796) (xy 0.20701 0.19685) (xy 0.21209 0.20701) (xy 0.2159 0.21717)
						(xy 0.21844 0.22733) (xy 0.22225 0.23876) (xy 0.22352 0.24892) (xy 0.22606 0.25908) (xy 0.22733 0.27051)
						(xy 0.22733 0.28067) (xy 0.2286 0.2921) (xy 0.22733 0.30353) (xy 0.22733 0.31369) (xy 0.22606 0.32512)
						(xy 0.22352 0.33528) (xy 0.22225 0.34544) (xy 0.21844 0.35687) (xy 0.2159 0.36703) (xy 0.21209 0.37719)
						(xy 0.20701 0.38735) (xy 0.2032 0.39624) (xy 0.19812 0.4064) (xy 0.17272 0.44196) (xy 0.1651 0.44958)
						(xy 0.1651 0.7366) (xy 0.16256 0.76835) (xy 0.1524 0.8001) (xy 0.13716 0.82804) (xy 0.11684 0.85344)
						(xy 0.09144 0.87376) (xy 0.0635 0.889) (xy 0.03175 0.89916)
					)
					(width 0)
					(fill yes)
				)
			)
		)
		(pad "103" smd custom
			(at 1.35001 4.106672 180)
			(size 0.1143 0.1143)
			(layers "F.Cu" "F.Mask" "F.Paste")
			(net "M_A_MA3")
			(options
				(clearance outline)
				(anchor circle)
			)
			(primitives
				(gr_poly
					(pts
						(xy 0 0.9017) (xy -0.03175 0.89916) (xy -0.0635 0.889) (xy -0.09144 0.87376) (xy -0.11684 0.85344)
						(xy -0.13716 0.82804) (xy -0.1524 0.8001) (xy -0.16256 0.76835) (xy -0.1651 0.7366) (xy -0.1651 0.11938)
						(xy -0.17272 0.11176) (xy -0.19812 0.0762) (xy -0.2032 0.06604) (xy -0.20701 0.05715) (xy -0.21209 0.04699)
						(xy -0.2159 0.03683) (xy -0.21844 0.02667) (xy -0.22225 0.01524) (xy -0.22352 0.00508) (xy -0.22606 -0.00508)
						(xy -0.22733 -0.01651) (xy -0.22733 -0.02667) (xy -0.2286 -0.0381) (xy -0.22733 -0.04953) (xy -0.22733 -0.05969)
						(xy -0.22606 -0.07112) (xy -0.22352 -0.08128) (xy -0.22225 -0.09144) (xy -0.21844 -0.10287) (xy -0.2159 -0.11303)
						(xy -0.21209 -0.12319) (xy -0.20701 -0.13335) (xy -0.2032 -0.14224) (xy -0.19812 -0.1524) (xy -0.17272 -0.18796)
						(xy -0.1651 -0.19558) (xy -0.1651 -0.7366) (xy -0.16256 -0.76835) (xy -0.1524 -0.8001) (xy -0.13716 -0.82804)
						(xy -0.11684 -0.85344) (xy -0.09144 -0.87376) (xy -0.0635 -0.889) (xy -0.03175 -0.89916) (xy 0 -0.9017)
						(xy 0.03175 -0.89916) (xy 0.0635 -0.889) (xy 0.09144 -0.87376) (xy 0.11684 -0.85344) (xy 0.13716 -0.82804)
						(xy 0.1524 -0.8001) (xy 0.16256 -0.76835) (xy 0.1651 -0.7366) (xy 0.1651 -0.19685) (xy 0.17272 -0.18923)
						(xy 0.17907 -0.18034) (xy 0.18669 -0.17145) (xy 0.19177 -0.16256) (xy 0.19812 -0.15367) (xy 0.20828 -0.13335)
						(xy 0.21971 -0.10287) (xy 0.22225 -0.09271) (xy 0.22479 -0.08128) (xy 0.22606 -0.07112) (xy 0.2286 -0.05969)
						(xy 0.2286 -0.01651) (xy 0.22606 -0.00508) (xy 0.22479 0.00508) (xy 0.22225 0.01651) (xy 0.21971 0.02667)
						(xy 0.20828 0.05715) (xy 0.19812 0.07747) (xy 0.19177 0.08636) (xy 0.18669 0.09525) (xy 0.17907 0.10414)
						(xy 0.17272 0.11303) (xy 0.1651 0.12065) (xy 0.1651 0.7366) (xy 0.16256 0.76835) (xy 0.1524 0.8001)
						(xy 0.13716 0.82804) (xy 0.11684 0.85344) (xy 0.09144 0.87376) (xy 0.0635 0.889) (xy 0.03175 0.89916)
					)
					(width 0)
					(fill yes)
				)
			)
		)
		(pad "104" smd custom
			(at 1.649984 -4.106672 180)
			(size 0.1143 0.1143)
			(layers "F.Cu" "F.Mask" "F.Paste")
			(net "M_A_MA4")
			(options
				(clearance outline)
				(anchor circle)
			)
			(primitives
				(gr_poly
					(pts
						(xy 0 0.9017) (xy -0.03175 0.89916) (xy -0.0635 0.889) (xy -0.09144 0.87376) (xy -0.11684 0.85344)
						(xy -0.13716 0.82804) (xy -0.1524 0.8001) (xy -0.16256 0.76835) (xy -0.1651 0.7366) (xy -0.1651 0.19685)
						(xy -0.17272 0.18923) (xy -0.17907 0.18034) (xy -0.18669 0.17145) (xy -0.19177 0.16256) (xy -0.19812 0.15367)
						(xy -0.20828 0.13335) (xy -0.21971 0.10287) (xy -0.22225 0.09271) (xy -0.22479 0.08128) (xy -0.22606 0.07112)
						(xy -0.2286 0.05969) (xy -0.2286 0.01651) (xy -0.22606 0.00508) (xy -0.22479 -0.00508) (xy -0.22225 -0.01651)
						(xy -0.21971 -0.02667) (xy -0.20828 -0.05715) (xy -0.19812 -0.07747) (xy -0.19177 -0.08636) (xy -0.18669 -0.09525)
						(xy -0.17907 -0.10414) (xy -0.17272 -0.11303) (xy -0.1651 -0.12065) (xy -0.1651 -0.7366) (xy -0.16256 -0.76835)
						(xy -0.1524 -0.8001) (xy -0.13716 -0.82804) (xy -0.11684 -0.85344) (xy -0.09144 -0.87376) (xy -0.0635 -0.889)
						(xy -0.03175 -0.89916) (xy 0 -0.9017) (xy 0.03175 -0.89916) (xy 0.0635 -0.889) (xy 0.09144 -0.87376)
						(xy 0.11684 -0.85344) (xy 0.13716 -0.82804) (xy 0.1524 -0.8001) (xy 0.16256 -0.76835) (xy 0.1651 -0.7366)
						(xy 0.1651 -0.11938) (xy 0.17272 -0.11176) (xy 0.19812 -0.0762) (xy 0.2032 -0.06604) (xy 0.20701 -0.05715)
						(xy 0.21209 -0.04699) (xy 0.2159 -0.03683) (xy 0.21844 -0.02667) (xy 0.22225 -0.01524) (xy 0.22352 -0.00508)
						(xy 0.22606 0.00508) (xy 0.22733 0.01651) (xy 0.22733 0.02667) (xy 0.2286 0.0381) (xy 0.22733 0.04953)
						(xy 0.22733 0.05969) (xy 0.22606 0.07112) (xy 0.22352 0.08128) (xy 0.22225 0.09144) (xy 0.21844 0.10287)
						(xy 0.2159 0.11303) (xy 0.21209 0.12319) (xy 0.20701 0.13335) (xy 0.2032 0.14224) (xy 0.19812 0.1524)
						(xy 0.17272 0.18796) (xy 0.1651 0.19558) (xy 0.1651 0.7366) (xy 0.16256 0.76835) (xy 0.1524 0.8001)
						(xy 0.13716 0.82804) (xy 0.11684 0.85344) (xy 0.09144 0.87376) (xy 0.0635 0.889) (xy 0.03175 0.89916)
					)
					(width 0)
					(fill yes)
				)
			)
		)
	)
)
